# TIMECARD (Time Appliance Project (Time Card)) — schematic netlist excerpt (pin names and nets, part order shuffled) for the footprints in the layout excerpt that follows; sources: Cadence DE-HDL packaged netlist, KiCad conversion of R4006-B0001-02_R01.brd

C103  CAPACITOR  0.1UF 10V 10%  pkg SMC_0402R_H022  page 14 : \1\ = XP3R3V_FPGA ; \2\ = SG
R432  RESISTOR  33OHM 1%  pkg SMC_0402R_H016  page 25 : \1\ = UNNAMED_16_CONNHDR2X6FSSMT_I1_7 ; \2\ = FPGA_IO_2

(kicad_pcb
	(version 20260206)
	(generator "pcbnew")
	(generator_version "10.0")
	(general
		(thickness 1.6)
		(legacy_teardrops no)
	)
	(paper "A4")
	(title_block
		(title "timecard-production-celestica-r4006 — R4006-B0001-02_R01.brd")
		(comment 1 "Time Appliance Project (Time Card) / footprints 901-902 of 1113")
	)
	(layers
		(0 "F.Cu" signal "TOP")
		(4 "In1.Cu" signal "L02_GND1")
		(6 "In2.Cu" signal "L03_SIG1")
		(8 "In3.Cu" signal "L04_GND2")
		(10 "In4.Cu" signal "L05_VCC1")
		(12 "In5.Cu" signal "L06_VCC2")
		(14 "In6.Cu" signal "L07_GND3")
		(16 "In7.Cu" signal "L08_SIG2")
		(18 "In8.Cu" signal "L09_GND4")
		(2 "B.Cu" signal "BOTTOM")
		(9 "F.Adhes" user "F.Adhesive")
		(11 "B.Adhes" user "B.Adhesive")
		(13 "F.Paste" user "Package Geometry/Pastemask Top")
		(15 "B.Paste" user "Package Geometry/Pastemask Bottom")
		(5 "F.SilkS" user "Ref Des/Silkscreen Top")
		(7 "B.SilkS" user "Ref Des/Silkscreen Bottom")
		(1 "F.Mask" user "Board Geometry/Soldermask Top")
		(3 "B.Mask" user "Board Geometry/Soldermask Bottom")
		(17 "Dwgs.User" user "User.Drawings")
		(19 "Cmts.User" user "User.Comments")
		(21 "Eco1.User" user "User.Eco1")
		(23 "Eco2.User" user "User.Eco2")
		(25 "Edge.Cuts" user "Board Geometry/Outline")
		(27 "Margin" user)
		(31 "F.CrtYd" user "Package Geometry/Place Bound Top")
		(29 "B.CrtYd" user "Package Geometry/Place Bound Bottom")
		(35 "F.Fab" user "Ref Des/Assembly Top")
		(33 "B.Fab" user "Ref Des/Assembly Bottom")
	)
	(footprint ""
		(layer "B.Cu")
		(at 151.892 -39.624 90)
		(property "Reference" "R432"
			(at -7.02437 0.635 0)
			(unlocked yes)
			(layer "B.SilkS")
			(effects
				(font
					(size 0.7874 0.5842)
					(thickness 0.1524)
				)
				(justify mirror)
			)
		)
		(property "Value" "VAL*"
			(at -0.02032 2.13233 90)
			(unlocked yes)
			(layer "B.Fab")
			(hide yes)
			(effects
				(font
					(size 0.7874 0.5842)
					(thickness 0.1524)
				)
				(justify mirror)
			)
		)
		(property "Tolerance" "TOL*"
			(at -0.044704 3.05435 90)
			(unlocked yes)
			(layer "Cmts.User")
			(hide yes)
			(effects
				(font
					(size 0.7874 0.5842)
					(thickness 0.1524)
				)
				(justify mirror)
			)
		)
		(property "User Part Number" "PARTNUM*"
			(at -0.02032 4.024884 90)
			(unlocked yes)
			(layer "Cmts.User")
			(hide yes)
			(effects
				(font
					(size 0.7874 0.5842)
					(thickness 0.1524)
				)
				(justify mirror)
			)
		)
		(property "Device Type" "RESISTOR-G155-133R0-01,33OHM,1%"
			(at -0.008382 1.210564 90)
			(unlocked yes)
			(layer "B.Fab")
			(hide yes)
			(effects
				(font
					(size 0.7874 0.5842)
					(thickness 0.1524)
				)
				(justify mirror)
			)
		)
		(duplicate_pad_numbers_are_jumpers no)
		(fp_line
			(start 1.143 -0.5588)
			(end 1.143 0.5588)
			(stroke
				(width 0.1)
				(type default)
			)
			(layer "B.SilkS")
		)
		(fp_line
			(start -1.143 -0.5588)
			(end 1.143 -0.5588)
			(stroke
				(width 0.1)
				(type default)
			)
			(layer "B.SilkS")
		)
		(fp_line
			(start 1.143 0.5588)
			(end -1.143 0.5588)
			(stroke
				(width 0.1)
				(type default)
			)
			(layer "B.SilkS")
		)
		(fp_line
			(start -1.143 0.5588)
			(end -1.143 -0.5588)
			(stroke
				(width 0.1)
				(type default)
			)
			(layer "B.SilkS")
		)
		(fp_poly
			(pts
				(xy 1.143 0.5588) (xy -1.143 0.5588) (xy -1.143 -0.5588) (xy 1.143 -0.5588)
			)
			(stroke
				(width 0)
				(type default)
			)
			(fill no)
			(layer "B.CrtYd")
		)
		(fp_line
			(start 0.508 -0.3048)
			(end 0.508 0.3048)
			(stroke
				(width 0.1)
				(type default)
			)
			(layer "B.Fab")
		)
		(fp_line
			(start -0.508 -0.3048)
			(end 0.508 -0.3048)
			(stroke
				(width 0.1)
				(type default)
			)
			(layer "B.Fab")
		)
		(fp_line
			(start 0.508 0.3048)
			(end -0.508 0.3048)
			(stroke
				(width 0.1)
				(type default)
			)
			(layer "B.Fab")
		)
		(fp_line
			(start -0.508 0.3048)
			(end -0.508 -0.3048)
			(stroke
				(width 0.1)
				(type default)
			)
			(layer "B.Fab")
		)
		(pad "1" smd rect
			(at 0.5334 0 270)
			(size 0.7112 0.6096)
			(layers "B.Cu" "B.Mask" "B.Paste")
			(net "UNNAMED_16_CONNHDR2X6FSSMT_I1_7")
		)
		(pad "2" smd rect
			(at -0.5334 0 270)
			(size 0.7112 0.6096)
			(layers "B.Cu" "B.Mask" "B.Paste")
			(net "FPGA_IO_2")
		)
		(zone
			(layer "B.Cu")
			(hatch none 0.5)
			(connect_pads
				(clearance 0)
			)
			(min_thickness 0.25)
			(keepout
				(tracks not_allowed)
				(vias allowed)
				(pads allowed)
				(copperpour not_allowed)
				(footprints allowed)
			)
			(placement
				(enabled no)
				(sheetname "")
			)
			(fill
				(thermal_gap 0.5)
				(thermal_bridge_width 0.5)
				(island_removal_mode 0)
			)
			(polygon
				(pts
					(xy 152.1968 -39.7002) (xy 151.5872 -39.7002) (xy 151.5872 -39.5478) (xy 152.1968 -39.5478)
				)
			)
		)
		(zone
			(layer "B.Cu")
			(hatch none 0.5)
			(connect_pads
				(clearance 0)
			)
			(min_thickness 0.25)
			(keepout
				(tracks allowed)
				(vias not_allowed)
				(pads allowed)
				(copperpour not_allowed)
				(footprints allowed)
			)
			(placement
				(enabled no)
				(sheetname "")
			)
			(fill
				(thermal_gap 0.5)
				(thermal_bridge_width 0.5)
				(island_removal_mode 0)
			)
			(polygon
				(pts
					(xy 152.1968 -39.7002) (xy 151.5872 -39.7002) (xy 151.5872 -39.5478) (xy 152.1968 -39.5478)
				)
			)
		)
	)
	(footprint ""
		(layer "B.Cu")
		(at 120.347232 -50.823114 180)
		(property "Reference" "C103"
			(at -0.175768 0.961136 0)
			(unlocked yes)
			(layer "B.SilkS")
			(effects
				(font
					(size 0.635 0.4064)
					(thickness 0.1524)
				)
				(justify mirror)
			)
		)
		(property "Value" "VAL*"
			(at 0 3.718306 180)
			(unlocked yes)
			(layer "B.Fab")
			(hide yes)
			(effects
				(font
					(size 0.7874 0.5842)
					(thickness 0.127)
				)
				(justify mirror)
			)
		)
		(property "Tolerance" "TOL*"
			(at 0 4.861306 180)
			(unlocked yes)
			(layer "Cmts.User")
			(hide yes)
			(effects
				(font
					(size 0.7874 0.5842)
					(thickness 0.127)
				)
				(justify mirror)
			)
		)
		(property "User Part Number" "PARTNUM*"
			(at 0 2.575306 180)
			(unlocked yes)
			(layer "Cmts.User")
			(hide yes)
			(effects
				(font
					(size 0.7874 0.5842)
					(thickness 0.127)
				)
				(justify mirror)
			)
		)
		(property "Device Type" "CAPACITOR-G105-0B104-CK,0.1UF,A"
			(at 0 1.432306 180)
			(unlocked yes)
			(layer "B.Fab")
			(hide yes)
			(effects
				(font
					(size 0.7874 0.5842)
					(thickness 0.127)
				)
				(justify mirror)
			)
		)
		(duplicate_pad_numbers_are_jumpers no)
		(fp_line
			(start 0.970026 0.4699)
			(end 0.970026 -0.4699)
			(stroke
				(width 0.1)
				(type default)
			)
			(layer "B.SilkS")
		)
		(fp_line
			(start 0.970026 -0.4699)
			(end -0.970026 -0.4699)
			(stroke
				(width 0.1)
				(type default)
			)
			(layer "B.SilkS")
		)
		(fp_line
			(start -0.970026 0.4699)
			(end 0.970026 0.4699)
			(stroke
				(width 0.1)
				(type default)
			)
			(layer "B.SilkS")
		)
		(fp_line
			(start -0.970026 -0.4699)
			(end -0.970026 0.4699)
			(stroke
				(width 0.1)
				(type default)
			)
			(layer "B.SilkS")
		)
		(fp_poly
			(pts
				(xy 0.970026 0.4699) (xy -0.970026 0.4699) (xy -0.970026 -0.4699) (xy 0.970026 -0.4699)
			)
			(stroke
				(width 0)
				(type default)
			)
			(fill no)
			(layer "B.CrtYd")
		)
		(fp_line
			(start 0.508 0.3048)
			(end 0.508 -0.3048)
			(stroke
				(width 0.1)
				(type default)
			)
			(layer "B.Fab")
		)
		(fp_line
			(start 0.508 -0.3048)
			(end -0.508 -0.3048)
			(stroke
				(width 0.1)
				(type default)
			)
			(layer "B.Fab")
		)
		(fp_line
			(start -0.508 0.3048)
			(end 0.508 0.3048)
			(stroke
				(width 0.1)
				(type default)
			)
			(layer "B.Fab")
		)
		(fp_line
			(start -0.508 -0.3048)
			(end -0.508 0.3048)
			(stroke
				(width 0.1)
				(type default)
			)
			(layer "B.Fab")
		)
		(pad "1" smd circle
			(at 0.500126 0)
			(size 0.635 0.635)
			(layers "B.Cu" "B.Mask" "B.Paste")
			(net "XP3R3V_FPGA")
		)
		(pad "2" smd circle
			(at -0.500126 0)
			(size 0.635 0.635)
			(layers "B.Cu" "B.Mask" "B.Paste")
			(net "SG")
		)
	)
)
